# T6G (Grand Teton) — schematic netlist excerpt (pin names and nets, part order shuffled) for the footprints in the layout excerpt that follows; sources: Cadence DE-HDL packaged netlist, KiCad conversion of 04192023_DAF0TMB3IC0_F0TG_MB_C_brd_V02_OCP.brd

R199  Q_RES  33 5% CHIP  pkg 0402LF  page 81 : A = E1S_0_P12V_EN ; B = P12V_E1S_0_EN
R8024  Q_RES  560 1% CHIP  pkg 0402LF  page 256 : A = LED_P12V_AUX_R3 ; B = P12V_AUX

(kicad_pcb
	(version 20260206)
	(generator "pcbnew")
	(generator_version "10.0")
	(general
		(thickness 1.6)
		(legacy_teardrops no)
	)
	(paper "A4")
	(title_block
		(title "04192023_DAF0TMB3IC0_F0TG_MB_C_brd_V02_OCP.brd")
		(comment 1 "Grand Teton / footprints 537-538 of 8354")
	)
	(layers
		(0 "F.Cu" signal "TOP")
		(4 "In1.Cu" signal "GND")
		(6 "In2.Cu" signal "IN1")
		(8 "In3.Cu" signal "GND1")
		(10 "In4.Cu" signal "IN2")
		(12 "In5.Cu" signal "GND2")
		(14 "In6.Cu" signal "IN3")
		(16 "In7.Cu" signal "GND3")
		(18 "In8.Cu" signal "VCC")
		(20 "In9.Cu" signal "VCC1")
		(22 "In10.Cu" signal "GND4")
		(24 "In11.Cu" signal "IN4")
		(26 "In12.Cu" signal "GND5")
		(28 "In13.Cu" signal "IN5")
		(30 "In14.Cu" signal "GND6")
		(32 "In15.Cu" signal "IN6")
		(34 "In16.Cu" signal "GND7")
		(2 "B.Cu" signal "BOTTOM")
		(9 "F.Adhes" user "F.Adhesive")
		(11 "B.Adhes" user "B.Adhesive")
		(13 "F.Paste" user "Package Geometry/Pastemask Top")
		(15 "B.Paste" user "Package Geometry/Pastemask Bottom")
		(5 "F.SilkS" user "Ref Des/Silkscreen Top")
		(7 "B.SilkS" user "Ref Des/Silkscreen Bottom")
		(1 "F.Mask" user "Board Geometry/Soldermask Top")
		(3 "B.Mask" user "Board Geometry/Soldermask Bottom")
		(17 "Dwgs.User" user "User.Drawings")
		(19 "Cmts.User" user "User.Comments")
		(21 "Eco1.User" user "User.Eco1")
		(23 "Eco2.User" user "User.Eco2")
		(25 "Edge.Cuts" user "Board Geometry/Outline")
		(27 "Margin" user)
		(31 "F.CrtYd" user "Package Geometry/Place Bound Top")
		(29 "B.CrtYd" user "Package Geometry/Place Bound Bottom")
		(35 "F.Fab" user "Ref Des/Assembly Top")
		(33 "B.Fab" user "Ref Des/Assembly Bottom")
	)
	(footprint ""
		(layer "F.Cu")
		(at 197.269608 -114.641376 180)
		(property "Reference" "R199"
			(at 0 0 180)
			(layer "F.SilkS")
			(hide yes)
			(effects
				(font
					(size 1.27 1.27)
				)
			)
		)
		(property "Value" ""
			(at 0 0 180)
			(layer "F.Fab")
			(effects
				(font
					(size 1.27 1.27)
				)
			)
		)
		(duplicate_pad_numbers_are_jumpers no)
		(fp_line
			(start 0.7874 0.4064)
			(end -0.7874 0.4064)
			(stroke
				(width 0.1524)
				(type default)
			)
			(layer "F.SilkS")
		)
		(fp_line
			(start 0.7874 -0.4064)
			(end 0.7874 0.4064)
			(stroke
				(width 0.1524)
				(type default)
			)
			(layer "F.SilkS")
		)
		(fp_line
			(start -0.7874 0.4064)
			(end -0.7874 -0.4064)
			(stroke
				(width 0.1524)
				(type default)
			)
			(layer "F.SilkS")
		)
		(fp_line
			(start -0.7874 -0.4064)
			(end 0.7874 -0.4064)
			(stroke
				(width 0.1524)
				(type default)
			)
			(layer "F.SilkS")
		)
		(fp_line
			(start 0.67945 0.3048)
			(end 0.120396 0.3048)
			(stroke
				(width 0.1)
				(type default)
			)
			(layer "F.Fab")
		)
		(fp_line
			(start 0.67945 -0.3048)
			(end 0.67945 0.3048)
			(stroke
				(width 0.1)
				(type default)
			)
			(layer "F.Fab")
		)
		(fp_line
			(start 0.12065 -0.2794)
			(end 0.12065 -0.3048)
			(stroke
				(width 0.1)
				(type default)
			)
			(layer "F.Fab")
		)
		(fp_line
			(start 0.12065 -0.3048)
			(end 0.67945 -0.3048)
			(stroke
				(width 0.1)
				(type default)
			)
			(layer "F.Fab")
		)
		(fp_line
			(start 0.120396 0.3048)
			(end 0.120396 0.2794)
			(stroke
				(width 0.1)
				(type default)
			)
			(layer "F.Fab")
		)
		(fp_line
			(start 0.120396 0.2794)
			(end -0.12065 0.2794)
			(stroke
				(width 0.1)
				(type default)
			)
			(layer "F.Fab")
		)
		(fp_line
			(start -0.12065 0.3048)
			(end -0.67945 0.3048)
			(stroke
				(width 0.1)
				(type default)
			)
			(layer "F.Fab")
		)
		(fp_line
			(start -0.12065 0.2794)
			(end -0.12065 0.3048)
			(stroke
				(width 0.1)
				(type default)
			)
			(layer "F.Fab")
		)
		(fp_line
			(start -0.12065 -0.2794)
			(end 0.12065 -0.2794)
			(stroke
				(width 0.1)
				(type default)
			)
			(layer "F.Fab")
		)
		(fp_line
			(start -0.12065 -0.305054)
			(end -0.12065 -0.2794)
			(stroke
				(width 0.1)
				(type default)
			)
			(layer "F.Fab")
		)
		(fp_line
			(start -0.67945 0.3048)
			(end -0.67945 -0.305054)
			(stroke
				(width 0.1)
				(type default)
			)
			(layer "F.Fab")
		)
		(fp_line
			(start -0.67945 -0.305054)
			(end -0.12065 -0.305054)
			(stroke
				(width 0.1)
				(type default)
			)
			(layer "F.Fab")
		)
		(pad "1" smd circle
			(at -0.40005 0 180)
			(size 0 0)
			(layers "F.Cu" "F.Mask" "F.Paste")
			(net "E1S_0_P12V_EN")
		)
		(pad "2" smd circle
			(at 0.40005 0 180)
			(size 0 0)
			(layers "F.Cu" "F.Mask" "F.Paste")
			(net "P12V_E1S_0_EN")
		)
	)
	(footprint ""
		(layer "F.Cu")
		(at 190.5 -44.577 180)
		(property "Reference" "R8024"
			(at 0 0 180)
			(layer "F.SilkS")
			(hide yes)
			(effects
				(font
					(size 1.27 1.27)
				)
			)
		)
		(property "Value" ""
			(at 0 0 180)
			(layer "F.Fab")
			(effects
				(font
					(size 1.27 1.27)
				)
			)
		)
		(duplicate_pad_numbers_are_jumpers no)
		(fp_line
			(start 0.7874 0.4064)
			(end -0.7874 0.4064)
			(stroke
				(width 0.1524)
				(type default)
			)
			(layer "F.SilkS")
		)
		(fp_line
			(start 0.7874 -0.4064)
			(end 0.7874 0.4064)
			(stroke
				(width 0.1524)
				(type default)
			)
			(layer "F.SilkS")
		)
		(fp_line
			(start -0.7874 0.4064)
			(end -0.7874 -0.4064)
			(stroke
				(width 0.1524)
				(type default)
			)
			(layer "F.SilkS")
		)
		(fp_line
			(start -0.7874 -0.4064)
			(end 0.7874 -0.4064)
			(stroke
				(width 0.1524)
				(type default)
			)
			(layer "F.SilkS")
		)
		(fp_line
			(start 0.67945 0.3048)
			(end 0.120396 0.3048)
			(stroke
				(width 0.1)
				(type default)
			)
			(layer "F.Fab")
		)
		(fp_line
			(start 0.67945 -0.3048)
			(end 0.67945 0.3048)
			(stroke
				(width 0.1)
				(type default)
			)
			(layer "F.Fab")
		)
		(fp_line
			(start 0.12065 -0.2794)
			(end 0.12065 -0.3048)
			(stroke
				(width 0.1)
				(type default)
			)
			(layer "F.Fab")
		)
		(fp_line
			(start 0.12065 -0.3048)
			(end 0.67945 -0.3048)
			(stroke
				(width 0.1)
				(type default)
			)
			(layer "F.Fab")
		)
		(fp_line
			(start 0.120396 0.3048)
			(end 0.120396 0.2794)
			(stroke
				(width 0.1)
				(type default)
			)
			(layer "F.Fab")
		)
		(fp_line
			(start 0.120396 0.2794)
			(end -0.12065 0.2794)
			(stroke
				(width 0.1)
				(type default)
			)
			(layer "F.Fab")
		)
		(fp_line
			(start -0.12065 0.3048)
			(end -0.67945 0.3048)
			(stroke
				(width 0.1)
				(type default)
			)
			(layer "F.Fab")
		)
		(fp_line
			(start -0.12065 0.2794)
			(end -0.12065 0.3048)
			(stroke
				(width 0.1)
				(type default)
			)
			(layer "F.Fab")
		)
		(fp_line
			(start -0.12065 -0.2794)
			(end 0.12065 -0.2794)
			(stroke
				(width 0.1)
				(type default)
			)
			(layer "F.Fab")
		)
		(fp_line
			(start -0.12065 -0.305054)
			(end -0.12065 -0.2794)
			(stroke
				(width 0.1)
				(type default)
			)
			(layer "F.Fab")
		)
		(fp_line
			(start -0.67945 0.3048)
			(end -0.67945 -0.305054)
			(stroke
				(width 0.1)
				(type default)
			)
			(layer "F.Fab")
		)
		(fp_line
			(start -0.67945 -0.305054)
			(end -0.12065 -0.305054)
			(stroke
				(width 0.1)
				(type default)
			)
			(layer "F.Fab")
		)
		(pad "1" smd circle
			(at -0.40005 0 180)
			(size 0 0)
			(layers "F.Cu" "F.Mask" "F.Paste")
			(net "LED_P12V_AUX_R3")
		)
		(pad "2" smd circle
			(at 0.40005 0 180)
			(size 0 0)
			(layers "F.Cu" "F.Mask" "F.Paste")
			(net "P12V_AUX")
		)
	)
)
